# T6G (Grand Teton) — schematic netlist excerpt (pin names and nets, part order shuffled) for the footprints in the layout excerpt that follows; sources: Cadence DE-HDL packaged netlist, KiCad conversion of 04192023_DAF0TMB3IC0_F0TG_MB_C_brd_V02_OCP.brd

PR6817  Q_RES  1K 1% EMPTY  pkg 0402LF  page 362 : A = P3V3_AUX ; B = TP_P0V9_RETIMER_CPU0_SVID_ALERT_N
C2627  Q_CAP  22UF 4V 20% X6S  pkg C0402  page 70 : A = PVDD11_S3_P0 ; B = GND

(kicad_pcb
	(version 20260206)
	(generator "pcbnew")
	(generator_version "10.0")
	(general
		(thickness 1.6)
		(legacy_teardrops no)
	)
	(paper "A4")
	(title_block
		(title "04192023_DAF0TMB3IC0_F0TG_MB_C_brd_V02_OCP.brd")
		(comment 1 "Grand Teton / footprints 658-659 of 8354")
	)
	(layers
		(0 "F.Cu" signal "TOP")
		(4 "In1.Cu" signal "GND")
		(6 "In2.Cu" signal "IN1")
		(8 "In3.Cu" signal "GND1")
		(10 "In4.Cu" signal "IN2")
		(12 "In5.Cu" signal "GND2")
		(14 "In6.Cu" signal "IN3")
		(16 "In7.Cu" signal "GND3")
		(18 "In8.Cu" signal "VCC")
		(20 "In9.Cu" signal "VCC1")
		(22 "In10.Cu" signal "GND4")
		(24 "In11.Cu" signal "IN4")
		(26 "In12.Cu" signal "GND5")
		(28 "In13.Cu" signal "IN5")
		(30 "In14.Cu" signal "GND6")
		(32 "In15.Cu" signal "IN6")
		(34 "In16.Cu" signal "GND7")
		(2 "B.Cu" signal "BOTTOM")
		(9 "F.Adhes" user "F.Adhesive")
		(11 "B.Adhes" user "B.Adhesive")
		(13 "F.Paste" user "Package Geometry/Pastemask Top")
		(15 "B.Paste" user "Package Geometry/Pastemask Bottom")
		(5 "F.SilkS" user "Ref Des/Silkscreen Top")
		(7 "B.SilkS" user "Ref Des/Silkscreen Bottom")
		(1 "F.Mask" user "Board Geometry/Soldermask Top")
		(3 "B.Mask" user "Board Geometry/Soldermask Bottom")
		(17 "Dwgs.User" user "User.Drawings")
		(19 "Cmts.User" user "User.Comments")
		(21 "Eco1.User" user "User.Eco1")
		(23 "Eco2.User" user "User.Eco2")
		(25 "Edge.Cuts" user "Board Geometry/Outline")
		(27 "Margin" user)
		(31 "F.CrtYd" user "Package Geometry/Place Bound Top")
		(29 "B.CrtYd" user "Package Geometry/Place Bound Bottom")
		(35 "F.Fab" user "Ref Des/Assembly Top")
		(33 "B.Fab" user "Ref Des/Assembly Bottom")
	)
	(footprint ""
		(layer "F.Cu")
		(at 353.900232 -262.204962 180)
		(property "Reference" "C2627"
			(at 0 0 180)
			(layer "F.SilkS")
			(hide yes)
			(effects
				(font
					(size 1.27 1.27)
				)
			)
		)
		(property "Value" ""
			(at 0 0 180)
			(layer "F.Fab")
			(effects
				(font
					(size 1.27 1.27)
				)
			)
		)
		(duplicate_pad_numbers_are_jumpers no)
		(fp_line
			(start 0.7874 0.4064)
			(end -0.7874 0.4064)
			(stroke
				(width 0.1524)
				(type default)
			)
			(layer "F.SilkS")
		)
		(fp_line
			(start 0.7874 -0.4064)
			(end 0.7874 0.4064)
			(stroke
				(width 0.1524)
				(type default)
			)
			(layer "F.SilkS")
		)
		(fp_line
			(start -0.7874 0.4064)
			(end -0.7874 -0.4064)
			(stroke
				(width 0.1524)
				(type default)
			)
			(layer "F.SilkS")
		)
		(fp_line
			(start -0.7874 -0.4064)
			(end 0.7874 -0.4064)
			(stroke
				(width 0.1524)
				(type default)
			)
			(layer "F.SilkS")
		)
		(fp_line
			(start 0.67945 0.3048)
			(end 0.120396 0.3048)
			(stroke
				(width 0.1)
				(type default)
			)
			(layer "F.Fab")
		)
		(fp_line
			(start 0.67945 -0.3048)
			(end 0.67945 0.3048)
			(stroke
				(width 0.1)
				(type default)
			)
			(layer "F.Fab")
		)
		(fp_line
			(start 0.12065 -0.2794)
			(end 0.12065 -0.3048)
			(stroke
				(width 0.1)
				(type default)
			)
			(layer "F.Fab")
		)
		(fp_line
			(start 0.12065 -0.3048)
			(end 0.67945 -0.3048)
			(stroke
				(width 0.1)
				(type default)
			)
			(layer "F.Fab")
		)
		(fp_line
			(start 0.120396 0.3048)
			(end 0.120396 0.2794)
			(stroke
				(width 0.1)
				(type default)
			)
			(layer "F.Fab")
		)
		(fp_line
			(start 0.120396 0.2794)
			(end -0.12065 0.2794)
			(stroke
				(width 0.1)
				(type default)
			)
			(layer "F.Fab")
		)
		(fp_line
			(start -0.12065 0.3048)
			(end -0.67945 0.3048)
			(stroke
				(width 0.1)
				(type default)
			)
			(layer "F.Fab")
		)
		(fp_line
			(start -0.12065 0.2794)
			(end -0.12065 0.3048)
			(stroke
				(width 0.1)
				(type default)
			)
			(layer "F.Fab")
		)
		(fp_line
			(start -0.12065 -0.2794)
			(end 0.12065 -0.2794)
			(stroke
				(width 0.1)
				(type default)
			)
			(layer "F.Fab")
		)
		(fp_line
			(start -0.12065 -0.305054)
			(end -0.12065 -0.2794)
			(stroke
				(width 0.1)
				(type default)
			)
			(layer "F.Fab")
		)
		(fp_line
			(start -0.67945 0.3048)
			(end -0.67945 -0.305054)
			(stroke
				(width 0.1)
				(type default)
			)
			(layer "F.Fab")
		)
		(fp_line
			(start -0.67945 -0.305054)
			(end -0.12065 -0.305054)
			(stroke
				(width 0.1)
				(type default)
			)
			(layer "F.Fab")
		)
		(pad "1" smd circle
			(at -0.40005 0 180)
			(size 0 0)
			(layers "F.Cu" "F.Mask" "F.Paste")
			(net "PVDD11_S3_P0")
		)
		(pad "2" smd circle
			(at 0.40005 0 180)
			(size 0 0)
			(layers "F.Cu" "F.Mask" "F.Paste")
			(net "GND")
		)
	)
	(footprint ""
		(layer "F.Cu")
		(at 439.029602 -421.37711)
		(property "Reference" "PR6817"
			(at 0 0 0)
			(layer "F.SilkS")
			(hide yes)
			(effects
				(font
					(size 1.27 1.27)
				)
			)
		)
		(property "Value" ""
			(at 0 0 0)
			(layer "F.Fab")
			(effects
				(font
					(size 1.27 1.27)
				)
			)
		)
		(duplicate_pad_numbers_are_jumpers no)
		(fp_line
			(start -0.7874 -0.4064)
			(end 0.7874 -0.4064)
			(stroke
				(width 0.1524)
				(type default)
			)
			(layer "F.SilkS")
		)
		(fp_line
			(start -0.7874 0.4064)
			(end -0.7874 -0.4064)
			(stroke
				(width 0.1524)
				(type default)
			)
			(layer "F.SilkS")
		)
		(fp_line
			(start 0.7874 -0.4064)
			(end 0.7874 0.4064)
			(stroke
				(width 0.1524)
				(type default)
			)
			(layer "F.SilkS")
		)
		(fp_line
			(start 0.7874 0.4064)
			(end -0.7874 0.4064)
			(stroke
				(width 0.1524)
				(type default)
			)
			(layer "F.SilkS")
		)
		(fp_line
			(start -0.67945 -0.305054)
			(end -0.12065 -0.305054)
			(stroke
				(width 0.1)
				(type default)
			)
			(layer "F.Fab")
		)
		(fp_line
			(start -0.67945 0.3048)
			(end -0.67945 -0.305054)
			(stroke
				(width 0.1)
				(type default)
			)
			(layer "F.Fab")
		)
		(fp_line
			(start -0.12065 -0.305054)
			(end -0.12065 -0.2794)
			(stroke
				(width 0.1)
				(type default)
			)
			(layer "F.Fab")
		)
		(fp_line
			(start -0.12065 -0.2794)
			(end 0.12065 -0.2794)
			(stroke
				(width 0.1)
				(type default)
			)
			(layer "F.Fab")
		)
		(fp_line
			(start -0.12065 0.2794)
			(end -0.12065 0.3048)
			(stroke
				(width 0.1)
				(type default)
			)
			(layer "F.Fab")
		)
		(fp_line
			(start -0.12065 0.3048)
			(end -0.67945 0.3048)
			(stroke
				(width 0.1)
				(type default)
			)
			(layer "F.Fab")
		)
		(fp_line
			(start 0.120396 0.2794)
			(end -0.12065 0.2794)
			(stroke
				(width 0.1)
				(type default)
			)
			(layer "F.Fab")
		)
		(fp_line
			(start 0.120396 0.3048)
			(end 0.120396 0.2794)
			(stroke
				(width 0.1)
				(type default)
			)
			(layer "F.Fab")
		)
		(fp_line
			(start 0.12065 -0.3048)
			(end 0.67945 -0.3048)
			(stroke
				(width 0.1)
				(type default)
			)
			(layer "F.Fab")
		)
		(fp_line
			(start 0.12065 -0.2794)
			(end 0.12065 -0.3048)
			(stroke
				(width 0.1)
				(type default)
			)
			(layer "F.Fab")
		)
		(fp_line
			(start 0.67945 -0.3048)
			(end 0.67945 0.3048)
			(stroke
				(width 0.1)
				(type default)
			)
			(layer "F.Fab")
		)
		(fp_line
			(start 0.67945 0.3048)
			(end 0.120396 0.3048)
			(stroke
				(width 0.1)
				(type default)
			)
			(layer "F.Fab")
		)
		(pad "1" smd circle
			(at -0.40005 0)
			(size 0 0)
			(layers "F.Cu" "F.Mask" "F.Paste")
			(net "P3V3_AUX")
		)
		(pad "2" smd circle
			(at 0.40005 0)
			(size 0 0)
			(layers "F.Cu" "F.Mask" "F.Paste")
			(net "TP_P0V9_RETIMER_CPU0_SVID_ALERT_N")
		)
	)
)
